# T6G (Grand Teton) — schematic netlist excerpt (pin names and nets, part order shuffled) for the footprints in the layout excerpt that follows; sources: Cadence DE-HDL packaged netlist, KiCad conversion of 04192023_DAF0TMB3IC0_F0TG_MB_C_brd_V02_OCP.brd

R3335  Q_RES  0 5% CHIP  pkg 0402LF  page 233 : A = CLK_100M_BMC_RC_DP_R ; B = CLK_100M_BMC_RC_DP
R3394  Q_RES  0 5% CHIP  pkg 0402LF  page 250 : A = SMB_IOEXP_3V3AUX_SDA_R ; B = SMB_IOEXP_3V3AUX_SDA
C48  Q_CAP_DIFFBUS  DIFF BUS_0.22UF 6.3V 20% X6S  pkg C0201  page 67 : \1\ = P5E_CPU1_P3_TX_C_DN<15> ; \2\ = P5E_CPU1_P3_TX_DN<15>

(kicad_pcb
	(version 20260206)
	(generator "pcbnew")
	(generator_version "10.0")
	(general
		(thickness 1.6)
		(legacy_teardrops no)
	)
	(paper "A4")
	(title_block
		(title "04192023_DAF0TMB3IC0_F0TG_MB_C_brd_V02_OCP.brd")
		(comment 1 "Grand Teton / footprints 648-650 of 8354")
	)
	(layers
		(0 "F.Cu" signal "TOP")
		(4 "In1.Cu" signal "GND")
		(6 "In2.Cu" signal "IN1")
		(8 "In3.Cu" signal "GND1")
		(10 "In4.Cu" signal "IN2")
		(12 "In5.Cu" signal "GND2")
		(14 "In6.Cu" signal "IN3")
		(16 "In7.Cu" signal "GND3")
		(18 "In8.Cu" signal "VCC")
		(20 "In9.Cu" signal "VCC1")
		(22 "In10.Cu" signal "GND4")
		(24 "In11.Cu" signal "IN4")
		(26 "In12.Cu" signal "GND5")
		(28 "In13.Cu" signal "IN5")
		(30 "In14.Cu" signal "GND6")
		(32 "In15.Cu" signal "IN6")
		(34 "In16.Cu" signal "GND7")
		(2 "B.Cu" signal "BOTTOM")
		(9 "F.Adhes" user "F.Adhesive")
		(11 "B.Adhes" user "B.Adhesive")
		(13 "F.Paste" user "Package Geometry/Pastemask Top")
		(15 "B.Paste" user "Package Geometry/Pastemask Bottom")
		(5 "F.SilkS" user "Ref Des/Silkscreen Top")
		(7 "B.SilkS" user "Ref Des/Silkscreen Bottom")
		(1 "F.Mask" user "Board Geometry/Soldermask Top")
		(3 "B.Mask" user "Board Geometry/Soldermask Bottom")
		(17 "Dwgs.User" user "User.Drawings")
		(19 "Cmts.User" user "User.Comments")
		(21 "Eco1.User" user "User.Eco1")
		(23 "Eco2.User" user "User.Eco2")
		(25 "Edge.Cuts" user "Board Geometry/Outline")
		(27 "Margin" user)
		(31 "F.CrtYd" user "Package Geometry/Place Bound Top")
		(29 "B.CrtYd" user "Package Geometry/Place Bound Bottom")
		(35 "F.Fab" user "Ref Des/Assembly Top")
		(33 "B.Fab" user "Ref Des/Assembly Bottom")
	)
	(footprint ""
		(layer "F.Cu")
		(at 279.513792 -118.70817 180)
		(property "Reference" "R3394"
			(at 0 0 180)
			(layer "F.SilkS")
			(hide yes)
			(effects
				(font
					(size 1.27 1.27)
				)
			)
		)
		(property "Value" ""
			(at 0 0 180)
			(layer "F.Fab")
			(effects
				(font
					(size 1.27 1.27)
				)
			)
		)
		(duplicate_pad_numbers_are_jumpers no)
		(fp_line
			(start 0.7874 0.4064)
			(end -0.7874 0.4064)
			(stroke
				(width 0.1524)
				(type default)
			)
			(layer "F.SilkS")
		)
		(fp_line
			(start 0.7874 -0.4064)
			(end 0.7874 0.4064)
			(stroke
				(width 0.1524)
				(type default)
			)
			(layer "F.SilkS")
		)
		(fp_line
			(start -0.7874 0.4064)
			(end -0.7874 -0.4064)
			(stroke
				(width 0.1524)
				(type default)
			)
			(layer "F.SilkS")
		)
		(fp_line
			(start -0.7874 -0.4064)
			(end 0.7874 -0.4064)
			(stroke
				(width 0.1524)
				(type default)
			)
			(layer "F.SilkS")
		)
		(fp_line
			(start 0.67945 0.3048)
			(end 0.120396 0.3048)
			(stroke
				(width 0.1)
				(type default)
			)
			(layer "F.Fab")
		)
		(fp_line
			(start 0.67945 -0.3048)
			(end 0.67945 0.3048)
			(stroke
				(width 0.1)
				(type default)
			)
			(layer "F.Fab")
		)
		(fp_line
			(start 0.12065 -0.2794)
			(end 0.12065 -0.3048)
			(stroke
				(width 0.1)
				(type default)
			)
			(layer "F.Fab")
		)
		(fp_line
			(start 0.12065 -0.3048)
			(end 0.67945 -0.3048)
			(stroke
				(width 0.1)
				(type default)
			)
			(layer "F.Fab")
		)
		(fp_line
			(start 0.120396 0.3048)
			(end 0.120396 0.2794)
			(stroke
				(width 0.1)
				(type default)
			)
			(layer "F.Fab")
		)
		(fp_line
			(start 0.120396 0.2794)
			(end -0.12065 0.2794)
			(stroke
				(width 0.1)
				(type default)
			)
			(layer "F.Fab")
		)
		(fp_line
			(start -0.12065 0.3048)
			(end -0.67945 0.3048)
			(stroke
				(width 0.1)
				(type default)
			)
			(layer "F.Fab")
		)
		(fp_line
			(start -0.12065 0.2794)
			(end -0.12065 0.3048)
			(stroke
				(width 0.1)
				(type default)
			)
			(layer "F.Fab")
		)
		(fp_line
			(start -0.12065 -0.2794)
			(end 0.12065 -0.2794)
			(stroke
				(width 0.1)
				(type default)
			)
			(layer "F.Fab")
		)
		(fp_line
			(start -0.12065 -0.305054)
			(end -0.12065 -0.2794)
			(stroke
				(width 0.1)
				(type default)
			)
			(layer "F.Fab")
		)
		(fp_line
			(start -0.67945 0.3048)
			(end -0.67945 -0.305054)
			(stroke
				(width 0.1)
				(type default)
			)
			(layer "F.Fab")
		)
		(fp_line
			(start -0.67945 -0.305054)
			(end -0.12065 -0.305054)
			(stroke
				(width 0.1)
				(type default)
			)
			(layer "F.Fab")
		)
		(pad "1" smd circle
			(at -0.40005 0 180)
			(size 0 0)
			(layers "F.Cu" "F.Mask" "F.Paste")
			(net "SMB_IOEXP_3V3AUX_SDA_R")
		)
		(pad "2" smd circle
			(at 0.40005 0 180)
			(size 0 0)
			(layers "F.Cu" "F.Mask" "F.Paste")
			(net "SMB_IOEXP_3V3AUX_SDA")
		)
	)
	(footprint ""
		(layer "F.Cu")
		(at 136.840976 -380.385828)
		(property "Reference" "C48"
			(at 0 0 0)
			(layer "F.SilkS")
			(hide yes)
			(effects
				(font
					(size 1.27 1.27)
				)
			)
		)
		(property "Value" ""
			(at 0 0 0)
			(layer "F.Fab")
			(effects
				(font
					(size 1.27 1.27)
				)
			)
		)
		(duplicate_pad_numbers_are_jumpers no)
		(fp_line
			(start -0.299974 -0.150114)
			(end 0.299974 -0.150114)
			(stroke
				(width 0.1)
				(type default)
			)
			(layer "F.Fab")
		)
		(fp_line
			(start -0.299974 0.150114)
			(end -0.299974 -0.150114)
			(stroke
				(width 0.1)
				(type default)
			)
			(layer "F.Fab")
		)
		(fp_line
			(start 0.299974 -0.150114)
			(end 0.299974 0.150114)
			(stroke
				(width 0.1)
				(type default)
			)
			(layer "F.Fab")
		)
		(fp_line
			(start 0.299974 0.150114)
			(end -0.299974 0.150114)
			(stroke
				(width 0.1)
				(type default)
			)
			(layer "F.Fab")
		)
		(pad "1" smd rect
			(at -0.2667 0)
			(size 0.3048 0.381)
			(layers "F.Cu" "F.Mask" "F.Paste")
			(net "P5E_CPU1_P3_TX_C_DN<15>")
		)
		(pad "2" smd rect
			(at 0.2667 0)
			(size 0.3048 0.381)
			(layers "F.Cu" "F.Mask" "F.Paste")
			(net "P5E_CPU1_P3_TX_DN<15>")
		)
	)
	(footprint ""
		(layer "F.Cu")
		(at 18.702782 -132.489702)
		(property "Reference" "R3335"
			(at 0 0 0)
			(layer "F.SilkS")
			(hide yes)
			(effects
				(font
					(size 1.27 1.27)
				)
			)
		)
		(property "Value" ""
			(at 0 0 0)
			(layer "F.Fab")
			(effects
				(font
					(size 1.27 1.27)
				)
			)
		)
		(duplicate_pad_numbers_are_jumpers no)
		(fp_line
			(start -0.7874 -0.4064)
			(end 0.7874 -0.4064)
			(stroke
				(width 0.1524)
				(type default)
			)
			(layer "F.SilkS")
		)
		(fp_line
			(start -0.7874 0.4064)
			(end -0.7874 -0.4064)
			(stroke
				(width 0.1524)
				(type default)
			)
			(layer "F.SilkS")
		)
		(fp_line
			(start 0.7874 -0.4064)
			(end 0.7874 0.4064)
			(stroke
				(width 0.1524)
				(type default)
			)
			(layer "F.SilkS")
		)
		(fp_line
			(start 0.7874 0.4064)
			(end -0.7874 0.4064)
			(stroke
				(width 0.1524)
				(type default)
			)
			(layer "F.SilkS")
		)
		(fp_line
			(start -0.67945 -0.305054)
			(end -0.12065 -0.305054)
			(stroke
				(width 0.1)
				(type default)
			)
			(layer "F.Fab")
		)
		(fp_line
			(start -0.67945 0.3048)
			(end -0.67945 -0.305054)
			(stroke
				(width 0.1)
				(type default)
			)
			(layer "F.Fab")
		)
		(fp_line
			(start -0.12065 -0.305054)
			(end -0.12065 -0.2794)
			(stroke
				(width 0.1)
				(type default)
			)
			(layer "F.Fab")
		)
		(fp_line
			(start -0.12065 -0.2794)
			(end 0.12065 -0.2794)
			(stroke
				(width 0.1)
				(type default)
			)
			(layer "F.Fab")
		)
		(fp_line
			(start -0.12065 0.2794)
			(end -0.12065 0.3048)
			(stroke
				(width 0.1)
				(type default)
			)
			(layer "F.Fab")
		)
		(fp_line
			(start -0.12065 0.3048)
			(end -0.67945 0.3048)
			(stroke
				(width 0.1)
				(type default)
			)
			(layer "F.Fab")
		)
		(fp_line
			(start 0.120396 0.2794)
			(end -0.12065 0.2794)
			(stroke
				(width 0.1)
				(type default)
			)
			(layer "F.Fab")
		)
		(fp_line
			(start 0.120396 0.3048)
			(end 0.120396 0.2794)
			(stroke
				(width 0.1)
				(type default)
			)
			(layer "F.Fab")
		)
		(fp_line
			(start 0.12065 -0.3048)
			(end 0.67945 -0.3048)
			(stroke
				(width 0.1)
				(type default)
			)
			(layer "F.Fab")
		)
		(fp_line
			(start 0.12065 -0.2794)
			(end 0.12065 -0.3048)
			(stroke
				(width 0.1)
				(type default)
			)
			(layer "F.Fab")
		)
		(fp_line
			(start 0.67945 -0.3048)
			(end 0.67945 0.3048)
			(stroke
				(width 0.1)
				(type default)
			)
			(layer "F.Fab")
		)
		(fp_line
			(start 0.67945 0.3048)
			(end 0.120396 0.3048)
			(stroke
				(width 0.1)
				(type default)
			)
			(layer "F.Fab")
		)
		(pad "1" smd circle
			(at -0.40005 0)
			(size 0 0)
			(layers "F.Cu" "F.Mask" "F.Paste")
			(net "CLK_100M_BMC_RC_DP_R")
		)
		(pad "2" smd circle
			(at 0.40005 0)
			(size 0 0)
			(layers "F.Cu" "F.Mask" "F.Paste")
			(net "CLK_100M_BMC_RC_DP")
		)
	)
)
